(kicad_pcb
	(version 20260206)
	(generator "pcbnew")
	(generator_version "10.0")
	(general
		(thickness 1.6)
		(legacy_teardrops no)
	)
	(paper "A4")
	(title_block
		(title "Bryce Canyon_IOM_IOC_16318-2_OCP.brd")
		(comment 1 "Bryce Canyon / footprint 360 of 1605 (CN1), pads 149-202 of 202")
	)
	(layers
		(0 "F.Cu" signal "TOP")
		(4 "In1.Cu" signal "L2GND")
		(6 "In2.Cu" signal "L3")
		(8 "In3.Cu" signal "L4VCC")
		(10 "In4.Cu" signal "L5VCC")
		(12 "In5.Cu" signal "L6")
		(14 "In6.Cu" signal "L7GND")
		(2 "B.Cu" signal "BOTTOM")
		(9 "F.Adhes" user "F.Adhesive")
		(11 "B.Adhes" user "B.Adhesive")
		(13 "F.Paste" user "Package Geometry/Pastemask Top")
		(15 "B.Paste" user "Package Geometry/Pastemask Bottom")
		(5 "F.SilkS" user "Ref Des/Silkscreen Top")
		(7 "B.SilkS" user "Ref Des/Silkscreen Bottom")
		(1 "F.Mask" user "Board Geometry/Soldermask Top")
		(3 "B.Mask" user "Board Geometry/Soldermask Bottom")
		(17 "Dwgs.User" user "User.Drawings")
		(19 "Cmts.User" user "User.Comments")
		(21 "Eco1.User" user "User.Eco1")
		(23 "Eco2.User" user "User.Eco2")
		(25 "Edge.Cuts" user "Board Geometry/Outline")
		(27 "Margin" user)
		(31 "F.CrtYd" user "Package Geometry/Place Bound Top")
		(29 "B.CrtYd" user "Package Geometry/Place Bound Bottom")
		(35 "F.Fab" user "Ref Des/Assembly Top")
		(33 "B.Fab" user "Ref Des/Assembly Bottom")
	)
	(footprint ""
		(layer "F.Cu")
		(at 141.299946 -44.200064 180)
		(property "Reference" "CN1"
			(at 0 0 180)
			(layer "F.SilkS")
			(hide yes)
			(effects
				(font
					(size 1.27 1.27)
				)
			)
		)
		(property "Value" "AMP-CONN200-13R-4-GP"
			(at 30.332934 43.515534 180)
			(unlocked yes)
			(layer "F.Fab")
			(hide yes)
			(effects
				(font
					(size 1.016 1.016)
					(thickness 0.1524)
				)
			)
		)
		(property "Device Type" "PREFIT-200P-360520-1H542"
			(at 30.332934 41.991534 180)
			(unlocked yes)
			(layer "F.Fab")
			(hide yes)
			(effects
				(font
					(size 1.016 1.016)
					(thickness 0.1524)
				)
			)
		)
		(duplicate_pad_numbers_are_jumpers no)
		(pad "GND35" thru_hole circle
			(at 12.599924 -8.50011 180)
			(size 0.762 0.762)
			(drill 0.359918)
			(layers "*.Cu" "*.Mask")
			(remove_unused_layers no)
			(net "GND")
			(clearance 0.1651)
			(thermal_gap 0.1651)
		)
		(pad "GND36" thru_hole circle
			(at 12.599924 -12.100052 180)
			(size 0.762 0.762)
			(drill 0.359918)
			(layers "*.Cu" "*.Mask")
			(remove_unused_layers no)
			(net "GND")
			(clearance 0.1651)
			(thermal_gap 0.1651)
		)
		(pad "GND37" thru_hole circle
			(at 21.599906 -2.500122 180)
			(size 0.762 0.762)
			(drill 0.359918)
			(layers "*.Cu" "*.Mask")
			(remove_unused_layers no)
			(net "GND")
			(clearance 0.1651)
			(thermal_gap 0.1651)
		)
		(pad "GND38" thru_hole circle
			(at 21.599906 -6.100064 180)
			(size 0.762 0.762)
			(drill 0.359918)
			(layers "*.Cu" "*.Mask")
			(remove_unused_layers no)
			(net "GND")
			(clearance 0.1651)
			(thermal_gap 0.1651)
		)
		(pad "GND39" thru_hole circle
			(at 21.599906 -9.700006 180)
			(size 0.762 0.762)
			(drill 0.359918)
			(layers "*.Cu" "*.Mask")
			(remove_unused_layers no)
			(net "GND")
			(clearance 0.1651)
			(thermal_gap 0.1651)
		)
		(pad "GND40" thru_hole circle
			(at 21.599906 -13.299948 180)
			(size 0.762 0.762)
			(drill 0.359918)
			(layers "*.Cu" "*.Mask")
			(remove_unused_layers no)
			(net "GND")
			(clearance 0.1651)
			(thermal_gap 0.1651)
		)
		(pad "GND41" thru_hole circle
			(at 23.400004 2.29997 180)
			(size 0.762 0.762)
			(drill 0.359918)
			(layers "*.Cu" "*.Mask")
			(remove_unused_layers no)
			(net "GND")
			(clearance 0.1651)
			(thermal_gap 0.1651)
		)
		(pad "GND42" thru_hole circle
			(at 23.400004 -1.299972 180)
			(size 0.762 0.762)
			(drill 0.359918)
			(layers "*.Cu" "*.Mask")
			(remove_unused_layers no)
			(net "GND")
			(clearance 0.1651)
			(thermal_gap 0.1651)
		)
		(pad "GND43" thru_hole circle
			(at 23.400004 -4.899914 180)
			(size 0.762 0.762)
			(drill 0.359918)
			(layers "*.Cu" "*.Mask")
			(remove_unused_layers no)
			(net "GND")
			(clearance 0.1651)
			(thermal_gap 0.1651)
		)
		(pad "GND44" thru_hole circle
			(at 23.400004 -8.50011 180)
			(size 0.762 0.762)
			(drill 0.359918)
			(layers "*.Cu" "*.Mask")
			(remove_unused_layers no)
			(net "GND")
			(clearance 0.1651)
			(thermal_gap 0.1651)
		)
		(pad "GND45" thru_hole circle
			(at 23.400004 -12.100052 180)
			(size 0.762 0.762)
			(drill 0.359918)
			(layers "*.Cu" "*.Mask")
			(remove_unused_layers no)
			(net "GND")
			(clearance 0.1651)
			(thermal_gap 0.1651)
		)
		(pad "GND46" thru_hole circle
			(at 25.200102 -2.500122 180)
			(size 0.762 0.762)
			(drill 0.359918)
			(layers "*.Cu" "*.Mask")
			(remove_unused_layers no)
			(net "GND")
			(clearance 0.1651)
			(thermal_gap 0.1651)
		)
		(pad "GND47" thru_hole circle
			(at 25.200102 -6.100064 180)
			(size 0.762 0.762)
			(drill 0.359918)
			(layers "*.Cu" "*.Mask")
			(remove_unused_layers no)
			(net "GND")
			(clearance 0.1651)
			(thermal_gap 0.1651)
		)
		(pad "GND48" thru_hole circle
			(at 25.200102 -9.700006 180)
			(size 0.762 0.762)
			(drill 0.359918)
			(layers "*.Cu" "*.Mask")
			(remove_unused_layers no)
			(net "GND")
			(clearance 0.1651)
			(thermal_gap 0.1651)
		)
		(pad "GND49" thru_hole circle
			(at 25.200102 -13.299948 180)
			(size 0.762 0.762)
			(drill 0.359918)
			(layers "*.Cu" "*.Mask")
			(remove_unused_layers no)
			(net "GND")
			(clearance 0.1651)
			(thermal_gap 0.1651)
		)
		(pad "GND50" thru_hole circle
			(at 26.999946 2.29997 180)
			(size 0.762 0.762)
			(drill 0.359918)
			(layers "*.Cu" "*.Mask")
			(remove_unused_layers no)
			(net "GND")
			(clearance 0.1651)
			(thermal_gap 0.1651)
		)
		(pad "GND51" thru_hole circle
			(at 26.999946 -1.299972 180)
			(size 0.762 0.762)
			(drill 0.359918)
			(layers "*.Cu" "*.Mask")
			(remove_unused_layers no)
			(net "GND")
			(clearance 0.1651)
			(thermal_gap 0.1651)
		)
		(pad "GND52" thru_hole circle
			(at 26.999946 -4.899914 180)
			(size 0.762 0.762)
			(drill 0.359918)
			(layers "*.Cu" "*.Mask")
			(remove_unused_layers no)
			(net "GND")
			(clearance 0.1651)
			(thermal_gap 0.1651)
		)
		(pad "GND53" thru_hole circle
			(at 26.999946 -8.50011 180)
			(size 0.762 0.762)
			(drill 0.359918)
			(layers "*.Cu" "*.Mask")
			(remove_unused_layers no)
			(net "GND")
			(clearance 0.1651)
			(thermal_gap 0.1651)
		)
		(pad "GND54" thru_hole circle
			(at 26.999946 -12.100052 180)
			(size 0.762 0.762)
			(drill 0.359918)
			(layers "*.Cu" "*.Mask")
			(remove_unused_layers no)
			(net "GND")
			(clearance 0.1651)
			(thermal_gap 0.1651)
		)
		(pad "GND55" thru_hole circle
			(at 28.800044 -2.500122 180)
			(size 0.762 0.762)
			(drill 0.359918)
			(layers "*.Cu" "*.Mask")
			(remove_unused_layers no)
			(net "GND")
			(clearance 0.1651)
			(thermal_gap 0.1651)
		)
		(pad "GND56" thru_hole circle
			(at 28.800044 -6.100064 180)
			(size 0.762 0.762)
			(drill 0.359918)
			(layers "*.Cu" "*.Mask")
			(remove_unused_layers no)
			(net "GND")
			(clearance 0.1651)
			(thermal_gap 0.1651)
		)
		(pad "GND57" thru_hole circle
			(at 28.800044 -9.700006 180)
			(size 0.762 0.762)
			(drill 0.359918)
			(layers "*.Cu" "*.Mask")
			(remove_unused_layers no)
			(net "GND")
			(clearance 0.1651)
			(thermal_gap 0.1651)
		)
		(pad "GND58" thru_hole circle
			(at 28.800044 -13.299948 180)
			(size 0.762 0.762)
			(drill 0.359918)
			(layers "*.Cu" "*.Mask")
			(remove_unused_layers no)
			(net "GND")
			(clearance 0.1651)
			(thermal_gap 0.1651)
		)
		(pad "GND59" thru_hole circle
			(at 30.599888 2.29997 180)
			(size 0.762 0.762)
			(drill 0.359918)
			(layers "*.Cu" "*.Mask")
			(remove_unused_layers no)
			(net "GND")
			(clearance 0.1651)
			(thermal_gap 0.1651)
		)
		(pad "GND60" thru_hole circle
			(at 30.599888 -1.299972 180)
			(size 0.762 0.762)
			(drill 0.359918)
			(layers "*.Cu" "*.Mask")
			(remove_unused_layers no)
			(net "GND")
			(clearance 0.1651)
			(thermal_gap 0.1651)
		)
		(pad "GND61" thru_hole circle
			(at 30.599888 -4.899914 180)
			(size 0.762 0.762)
			(drill 0.359918)
			(layers "*.Cu" "*.Mask")
			(remove_unused_layers no)
			(net "GND")
			(clearance 0.1651)
			(thermal_gap 0.1651)
		)
		(pad "GND62" thru_hole circle
			(at 30.599888 -8.50011 180)
			(size 0.762 0.762)
			(drill 0.359918)
			(layers "*.Cu" "*.Mask")
			(remove_unused_layers no)
			(net "GND")
			(clearance 0.1651)
			(thermal_gap 0.1651)
		)
		(pad "GND63" thru_hole circle
			(at 30.599888 -12.100052 180)
			(size 0.762 0.762)
			(drill 0.359918)
			(layers "*.Cu" "*.Mask")
			(remove_unused_layers no)
			(net "GND")
			(clearance 0.1651)
			(thermal_gap 0.1651)
		)
		(pad "GND64" thru_hole circle
			(at 32.399986 -2.500122 180)
			(size 0.762 0.762)
			(drill 0.359918)
			(layers "*.Cu" "*.Mask")
			(remove_unused_layers no)
			(net "GND")
			(clearance 0.1651)
			(thermal_gap 0.1651)
		)
		(pad "GND65" thru_hole circle
			(at 32.399986 -6.100064 180)
			(size 0.762 0.762)
			(drill 0.359918)
			(layers "*.Cu" "*.Mask")
			(remove_unused_layers no)
			(net "GND")
			(clearance 0.1651)
			(thermal_gap 0.1651)
		)
		(pad "GND66" thru_hole circle
			(at 32.399986 -9.700006 180)
			(size 0.762 0.762)
			(drill 0.359918)
			(layers "*.Cu" "*.Mask")
			(remove_unused_layers no)
			(net "GND")
			(clearance 0.1651)
			(thermal_gap 0.1651)
		)
		(pad "GND67" thru_hole circle
			(at 32.399986 -13.299948 180)
			(size 0.762 0.762)
			(drill 0.359918)
			(layers "*.Cu" "*.Mask")
			(remove_unused_layers no)
			(net "GND")
			(clearance 0.1651)
			(thermal_gap 0.1651)
		)
		(pad "GND68" thru_hole circle
			(at 34.200084 2.29997 180)
			(size 0.762 0.762)
			(drill 0.359918)
			(layers "*.Cu" "*.Mask")
			(remove_unused_layers no)
			(net "GND")
			(clearance 0.1651)
			(thermal_gap 0.1651)
		)
		(pad "GND69" thru_hole circle
			(at 34.200084 -1.299972 180)
			(size 0.762 0.762)
			(drill 0.359918)
			(layers "*.Cu" "*.Mask")
			(remove_unused_layers no)
			(net "GND")
			(clearance 0.1651)
			(thermal_gap 0.1651)
		)
		(pad "GND70" thru_hole circle
			(at 34.200084 -4.899914 180)
			(size 0.762 0.762)
			(drill 0.359918)
			(layers "*.Cu" "*.Mask")
			(remove_unused_layers no)
			(net "GND")
			(clearance 0.1651)
			(thermal_gap 0.1651)
		)
		(pad "GND71" thru_hole circle
			(at 34.200084 -8.50011 180)
			(size 0.762 0.762)
			(drill 0.359918)
			(layers "*.Cu" "*.Mask")
			(remove_unused_layers no)
			(net "GND")
			(clearance 0.1651)
			(thermal_gap 0.1651)
		)
		(pad "GND72" thru_hole circle
			(at 34.200084 -12.100052 180)
			(size 0.762 0.762)
			(drill 0.359918)
			(layers "*.Cu" "*.Mask")
			(remove_unused_layers no)
			(net "GND")
			(clearance 0.1651)
			(thermal_gap 0.1651)
		)
		(pad "H1" thru_hole circle
			(at 0 -12.199874 180)
			(size 0.762 0.762)
			(drill 0.359918)
			(layers "*.Cu" "*.Mask")
			(remove_unused_layers no)
			(net "PCIE_COMP_TO_IOM_8_DP")
			(clearance 0.1651)
			(thermal_gap 0.1651)
		)
		(pad "H2" thru_hole circle
			(at 1.800098 -10.999978 180)
			(size 0.762 0.762)
			(drill 0.359918)
			(layers "*.Cu" "*.Mask")
			(remove_unused_layers no)
			(net "PCIE_COMP_TO_IOM_9_DP")
			(clearance 0.1651)
			(thermal_gap 0.1651)
		)
		(pad "H3" thru_hole circle
			(at 3.599942 -12.199874 180)
			(size 0.762 0.762)
			(drill 0.359918)
			(layers "*.Cu" "*.Mask")
			(remove_unused_layers no)
			(net "PCIE_COMP_TO_IOM_10_DP")
			(clearance 0.1651)
			(thermal_gap 0.1651)
		)
		(pad "H4" thru_hole circle
			(at 5.40004 -10.999978 180)
			(size 0.762 0.762)
			(drill 0.359918)
			(layers "*.Cu" "*.Mask")
			(remove_unused_layers no)
			(net "PCIE_COMP_TO_IOM_11_DP")
			(clearance 0.1651)
			(thermal_gap 0.1651)
		)
		(pad "H5" thru_hole circle
			(at 7.199884 -12.199874 180)
			(size 0.762 0.762)
			(drill 0.359918)
			(layers "*.Cu" "*.Mask")
			(remove_unused_layers no)
			(net "PCIE_COMP_TO_IOM_12_DP")
			(clearance 0.1651)
			(thermal_gap 0.1651)
		)
		(pad "H6" thru_hole circle
			(at 8.999982 -10.999978 180)
			(size 0.762 0.762)
			(drill 0.359918)
			(layers "*.Cu" "*.Mask")
			(remove_unused_layers no)
			(net "PCIE_COMP_TO_IOM_13_DP")
			(clearance 0.1651)
			(thermal_gap 0.1651)
		)
		(pad "H7" thru_hole circle
			(at 10.80008 -12.199874 180)
			(size 0.762 0.762)
			(drill 0.359918)
			(layers "*.Cu" "*.Mask")
			(remove_unused_layers no)
			(net "PCIE_COMP_TO_IOM_14_DP")
			(clearance 0.1651)
			(thermal_gap 0.1651)
		)
		(pad "H8" thru_hole circle
			(at 12.599924 -10.999978 180)
			(size 0.762 0.762)
			(drill 0.359918)
			(layers "*.Cu" "*.Mask")
			(remove_unused_layers no)
			(net "PCIE_COMP_TO_IOM_15_DP")
			(clearance 0.1651)
			(thermal_gap 0.1651)
		)
		(pad "H9" thru_hole circle
			(at 21.599906 -12.199874 180)
			(size 0.762 0.762)
			(drill 0.359918)
			(layers "*.Cu" "*.Mask")
			(remove_unused_layers no)
			(net "PCIE_COMP_TO_IOM_16_DP")
			(clearance 0.1651)
			(thermal_gap 0.1651)
		)
		(pad "H10" thru_hole circle
			(at 23.400004 -10.999978 180)
			(size 0.762 0.762)
			(drill 0.359918)
			(layers "*.Cu" "*.Mask")
			(remove_unused_layers no)
			(net "PCIE_COMP_TO_IOM_17_DP")
			(clearance 0.1651)
			(thermal_gap 0.1651)
		)
		(pad "H11" thru_hole circle
			(at 25.200102 -12.199874 180)
			(size 0.762 0.762)
			(drill 0.359918)
			(layers "*.Cu" "*.Mask")
			(remove_unused_layers no)
			(net "PCIE_COMP_TO_IOM_18_DP")
			(clearance 0.1651)
			(thermal_gap 0.1651)
		)
		(pad "H12" thru_hole circle
			(at 26.999946 -10.999978 180)
			(size 0.762 0.762)
			(drill 0.359918)
			(layers "*.Cu" "*.Mask")
			(remove_unused_layers no)
			(net "PCIE_COMP_TO_IOM_19_DP")
			(clearance 0.1651)
			(thermal_gap 0.1651)
		)
		(pad "H13" thru_hole circle
			(at 28.800044 -12.199874 180)
			(size 0.762 0.762)
			(drill 0.359918)
			(layers "*.Cu" "*.Mask")
			(remove_unused_layers no)
			(net "PCIE_COMP_TO_IOM_20_DP")
			(clearance 0.1651)
			(thermal_gap 0.1651)
		)
		(pad "H14" thru_hole circle
			(at 30.599888 -10.999978 180)
			(size 0.762 0.762)
			(drill 0.359918)
			(layers "*.Cu" "*.Mask")
			(remove_unused_layers no)
			(net "PCIE_COMP_TO_IOM_21_DP")
			(clearance 0.1651)
			(thermal_gap 0.1651)
		)
		(pad "H15" thru_hole circle
			(at 32.399986 -12.199874 180)
			(size 0.762 0.762)
			(drill 0.359918)
			(layers "*.Cu" "*.Mask")
			(remove_unused_layers no)
			(net "PCIE_COMP_TO_IOM_22_DP")
			(clearance 0.1651)
			(thermal_gap 0.1651)
		)
		(pad "H16" thru_hole circle
			(at 34.200084 -10.999978 180)
			(size 0.762 0.762)
			(drill 0.359918)
			(layers "*.Cu" "*.Mask")
			(remove_unused_layers no)
			(net "PCIE_COMP_TO_IOM_23_DP")
			(clearance 0.1651)
			(thermal_gap 0.1651)
		)
	)
)
